# T6G (Grand Teton) — schematic netlist excerpt (pin names and nets, part order shuffled) for the footprints in the layout excerpt that follows; sources: Cadence DE-HDL packaged netlist, KiCad conversion of 04192023_DAF0TMB3IC0_F0TG_MB_C_brd_V02_OCP.brd

C2147  Q_CAP  22UF 4V 20% X6S  pkg C0402  page 68 : A = PVDDCR_SOC_P0 ; B = GND
C2656  Q_CAP  22UF 4V 20% X6S  pkg C0402  page 70 : A = PVDD11_S3_P0 ; B = GND

(kicad_pcb
	(version 20260206)
	(generator "pcbnew")
	(generator_version "10.0")
	(general
		(thickness 1.6)
		(legacy_teardrops no)
	)
	(paper "A4")
	(title_block
		(title "04192023_DAF0TMB3IC0_F0TG_MB_C_brd_V02_OCP.brd")
		(comment 1 "Grand Teton / footprints 5074-5075 of 8354")
	)
	(layers
		(0 "F.Cu" signal "TOP")
		(4 "In1.Cu" signal "GND")
		(6 "In2.Cu" signal "IN1")
		(8 "In3.Cu" signal "GND1")
		(10 "In4.Cu" signal "IN2")
		(12 "In5.Cu" signal "GND2")
		(14 "In6.Cu" signal "IN3")
		(16 "In7.Cu" signal "GND3")
		(18 "In8.Cu" signal "VCC")
		(20 "In9.Cu" signal "VCC1")
		(22 "In10.Cu" signal "GND4")
		(24 "In11.Cu" signal "IN4")
		(26 "In12.Cu" signal "GND5")
		(28 "In13.Cu" signal "IN5")
		(30 "In14.Cu" signal "GND6")
		(32 "In15.Cu" signal "IN6")
		(34 "In16.Cu" signal "GND7")
		(2 "B.Cu" signal "BOTTOM")
		(9 "F.Adhes" user "F.Adhesive")
		(11 "B.Adhes" user "B.Adhesive")
		(13 "F.Paste" user "Package Geometry/Pastemask Top")
		(15 "B.Paste" user "Package Geometry/Pastemask Bottom")
		(5 "F.SilkS" user "Ref Des/Silkscreen Top")
		(7 "B.SilkS" user "Ref Des/Silkscreen Bottom")
		(1 "F.Mask" user "Board Geometry/Soldermask Top")
		(3 "B.Mask" user "Board Geometry/Soldermask Bottom")
		(17 "Dwgs.User" user "User.Drawings")
		(19 "Cmts.User" user "User.Comments")
		(21 "Eco1.User" user "User.Eco1")
		(23 "Eco2.User" user "User.Eco2")
		(25 "Edge.Cuts" user "Board Geometry/Outline")
		(27 "Margin" user)
		(31 "F.CrtYd" user "Package Geometry/Place Bound Top")
		(29 "B.CrtYd" user "Package Geometry/Place Bound Bottom")
		(35 "F.Fab" user "Ref Des/Assembly Top")
		(33 "B.Fab" user "Ref Des/Assembly Bottom")
	)
	(footprint ""
		(layer "B.Cu")
		(at 363.804454 -266.00531)
		(property "Reference" "C2656"
			(at 0 0 0)
			(layer "B.SilkS")
			(hide yes)
			(effects
				(font
					(size 1.27 1.27)
				)
				(justify mirror)
			)
		)
		(property "Value" ""
			(at 0 0 0)
			(layer "B.Fab")
			(effects
				(font
					(size 1.27 1.27)
				)
				(justify mirror)
			)
		)
		(duplicate_pad_numbers_are_jumpers no)
		(fp_line
			(start -0.7874 -0.4064)
			(end -0.7874 0.4064)
			(stroke
				(width 0.1524)
				(type default)
			)
			(layer "B.SilkS")
		)
		(fp_line
			(start -0.7874 0.4064)
			(end 0.7874 0.4064)
			(stroke
				(width 0.1524)
				(type default)
			)
			(layer "B.SilkS")
		)
		(fp_line
			(start 0.7874 -0.4064)
			(end -0.7874 -0.4064)
			(stroke
				(width 0.1524)
				(type default)
			)
			(layer "B.SilkS")
		)
		(fp_line
			(start 0.7874 0.4064)
			(end 0.7874 -0.4064)
			(stroke
				(width 0.1524)
				(type default)
			)
			(layer "B.SilkS")
		)
		(fp_line
			(start -0.67945 -0.3048)
			(end -0.67945 0.3048)
			(stroke
				(width 0.1)
				(type default)
			)
			(layer "B.Fab")
		)
		(fp_line
			(start -0.67945 0.3048)
			(end -0.120396 0.3048)
			(stroke
				(width 0.1)
				(type default)
			)
			(layer "B.Fab")
		)
		(fp_line
			(start -0.12065 -0.3048)
			(end -0.67945 -0.3048)
			(stroke
				(width 0.1)
				(type default)
			)
			(layer "B.Fab")
		)
		(fp_line
			(start -0.12065 -0.2794)
			(end -0.12065 -0.3048)
			(stroke
				(width 0.1)
				(type default)
			)
			(layer "B.Fab")
		)
		(fp_line
			(start -0.120396 0.2794)
			(end 0.12065 0.2794)
			(stroke
				(width 0.1)
				(type default)
			)
			(layer "B.Fab")
		)
		(fp_line
			(start -0.120396 0.3048)
			(end -0.120396 0.2794)
			(stroke
				(width 0.1)
				(type default)
			)
			(layer "B.Fab")
		)
		(fp_line
			(start 0.12065 -0.305054)
			(end 0.12065 -0.2794)
			(stroke
				(width 0.1)
				(type default)
			)
			(layer "B.Fab")
		)
		(fp_line
			(start 0.12065 -0.2794)
			(end -0.12065 -0.2794)
			(stroke
				(width 0.1)
				(type default)
			)
			(layer "B.Fab")
		)
		(fp_line
			(start 0.12065 0.2794)
			(end 0.12065 0.3048)
			(stroke
				(width 0.1)
				(type default)
			)
			(layer "B.Fab")
		)
		(fp_line
			(start 0.12065 0.3048)
			(end 0.67945 0.3048)
			(stroke
				(width 0.1)
				(type default)
			)
			(layer "B.Fab")
		)
		(fp_line
			(start 0.67945 -0.305054)
			(end 0.12065 -0.305054)
			(stroke
				(width 0.1)
				(type default)
			)
			(layer "B.Fab")
		)
		(fp_line
			(start 0.67945 0.3048)
			(end 0.67945 -0.305054)
			(stroke
				(width 0.1)
				(type default)
			)
			(layer "B.Fab")
		)
		(pad "1" smd circle
			(at 0.40005 0 180)
			(size 0 0)
			(layers "B.Cu" "B.Mask" "B.Paste")
			(net "PVDD11_S3_P0")
		)
		(pad "2" smd circle
			(at -0.40005 0 180)
			(size 0 0)
			(layers "B.Cu" "B.Mask" "B.Paste")
			(net "GND")
		)
	)
	(footprint ""
		(layer "B.Cu")
		(at 365.835692 -256.505202)
		(property "Reference" "C2147"
			(at 0 0 0)
			(layer "B.SilkS")
			(hide yes)
			(effects
				(font
					(size 1.27 1.27)
				)
				(justify mirror)
			)
		)
		(property "Value" ""
			(at 0 0 0)
			(layer "B.Fab")
			(effects
				(font
					(size 1.27 1.27)
				)
				(justify mirror)
			)
		)
		(duplicate_pad_numbers_are_jumpers no)
		(fp_line
			(start -0.7874 -0.4064)
			(end -0.7874 0.4064)
			(stroke
				(width 0.1524)
				(type default)
			)
			(layer "B.SilkS")
		)
		(fp_line
			(start -0.7874 0.4064)
			(end 0.7874 0.4064)
			(stroke
				(width 0.1524)
				(type default)
			)
			(layer "B.SilkS")
		)
		(fp_line
			(start 0.7874 -0.4064)
			(end -0.7874 -0.4064)
			(stroke
				(width 0.1524)
				(type default)
			)
			(layer "B.SilkS")
		)
		(fp_line
			(start 0.7874 0.4064)
			(end 0.7874 -0.4064)
			(stroke
				(width 0.1524)
				(type default)
			)
			(layer "B.SilkS")
		)
		(fp_line
			(start -0.67945 -0.3048)
			(end -0.67945 0.3048)
			(stroke
				(width 0.1)
				(type default)
			)
			(layer "B.Fab")
		)
		(fp_line
			(start -0.67945 0.3048)
			(end -0.120396 0.3048)
			(stroke
				(width 0.1)
				(type default)
			)
			(layer "B.Fab")
		)
		(fp_line
			(start -0.12065 -0.3048)
			(end -0.67945 -0.3048)
			(stroke
				(width 0.1)
				(type default)
			)
			(layer "B.Fab")
		)
		(fp_line
			(start -0.12065 -0.2794)
			(end -0.12065 -0.3048)
			(stroke
				(width 0.1)
				(type default)
			)
			(layer "B.Fab")
		)
		(fp_line
			(start -0.120396 0.2794)
			(end 0.12065 0.2794)
			(stroke
				(width 0.1)
				(type default)
			)
			(layer "B.Fab")
		)
		(fp_line
			(start -0.120396 0.3048)
			(end -0.120396 0.2794)
			(stroke
				(width 0.1)
				(type default)
			)
			(layer "B.Fab")
		)
		(fp_line
			(start 0.12065 -0.305054)
			(end 0.12065 -0.2794)
			(stroke
				(width 0.1)
				(type default)
			)
			(layer "B.Fab")
		)
		(fp_line
			(start 0.12065 -0.2794)
			(end -0.12065 -0.2794)
			(stroke
				(width 0.1)
				(type default)
			)
			(layer "B.Fab")
		)
		(fp_line
			(start 0.12065 0.2794)
			(end 0.12065 0.3048)
			(stroke
				(width 0.1)
				(type default)
			)
			(layer "B.Fab")
		)
		(fp_line
			(start 0.12065 0.3048)
			(end 0.67945 0.3048)
			(stroke
				(width 0.1)
				(type default)
			)
			(layer "B.Fab")
		)
		(fp_line
			(start 0.67945 -0.305054)
			(end 0.12065 -0.305054)
			(stroke
				(width 0.1)
				(type default)
			)
			(layer "B.Fab")
		)
		(fp_line
			(start 0.67945 0.3048)
			(end 0.67945 -0.305054)
			(stroke
				(width 0.1)
				(type default)
			)
			(layer "B.Fab")
		)
		(pad "1" smd circle
			(at 0.40005 0 180)
			(size 0 0)
			(layers "B.Cu" "B.Mask" "B.Paste")
			(net "PVDDCR_SOC_P0")
		)
		(pad "2" smd circle
			(at -0.40005 0 180)
			(size 0 0)
			(layers "B.Cu" "B.Mask" "B.Paste")
			(net "GND")
		)
	)
)
